(kicad_pcb
	(version 20260206)
	(generator "pcbnew")
	(generator_version "10.0")
	(general
		(thickness 1.6)
		(legacy_teardrops no)
	)
	(paper "A4")
	(title_block
		(title "9052_F0T_PDB_Converter_Brick_F_V03_1208_1600_OCP.brd")
		(comment 1 "Grand Teton / footprints 499-503 of 578")
	)
	(layers
		(0 "F.Cu" signal "TOP")
		(4 "In1.Cu" signal "GND")
		(6 "In2.Cu" signal "IN1")
		(8 "In3.Cu" signal "GND1")
		(10 "In4.Cu" signal "VCC")
		(12 "In5.Cu" signal "VCC1")
		(14 "In6.Cu" signal "GND2")
		(16 "In7.Cu" signal "IN2")
		(18 "In8.Cu" signal "GND3")
		(2 "B.Cu" signal "BOTTOM")
		(9 "F.Adhes" user "F.Adhesive")
		(11 "B.Adhes" user "B.Adhesive")
		(13 "F.Paste" user "Package Geometry/Pastemask Top")
		(15 "B.Paste" user "Package Geometry/Pastemask Bottom")
		(5 "F.SilkS" user "Ref Des/Silkscreen Top")
		(7 "B.SilkS" user "Ref Des/Silkscreen Bottom")
		(1 "F.Mask" user "Board Geometry/Soldermask Top")
		(3 "B.Mask" user "Board Geometry/Soldermask Bottom")
		(17 "Dwgs.User" user "User.Drawings")
		(19 "Cmts.User" user "User.Comments")
		(21 "Eco1.User" user "User.Eco1")
		(23 "Eco2.User" user "User.Eco2")
		(25 "Edge.Cuts" user "Board Geometry/Outline")
		(27 "Margin" user)
		(31 "F.CrtYd" user "Package Geometry/Place Bound Top")
		(29 "B.CrtYd" user "Package Geometry/Place Bound Bottom")
		(35 "F.Fab" user "Ref Des/Assembly Top")
		(33 "B.Fab" user "Ref Des/Assembly Bottom")
	)
	(footprint ""
		(layer "B.Cu")
		(at 276.352 -38.862 -90)
		(property "Reference" "U40"
			(at 0.92837 1.6891 0)
			(unlocked yes)
			(layer "B.SilkS")
			(effects
				(font
					(size 0.7874 0.5842)
					(thickness 0.1524)
				)
				(justify left mirror)
			)
		)
		(property "Value" ""
			(at 0 0 90)
			(layer "B.Fab")
			(effects
				(font
					(size 1.27 1.27)
				)
				(justify mirror)
			)
		)
		(duplicate_pad_numbers_are_jumpers no)
		(fp_line
			(start -1.603248 1.500124)
			(end 1.603248 1.500124)
			(stroke
				(width 0.1524)
				(type default)
			)
			(layer "B.SilkS")
		)
		(fp_line
			(start 1.603248 1.500124)
			(end 1.603248 -1.500124)
			(stroke
				(width 0.1524)
				(type default)
			)
			(layer "B.SilkS")
		)
		(fp_line
			(start -1.603248 -1.500124)
			(end -1.603248 1.500124)
			(stroke
				(width 0.1524)
				(type default)
			)
			(layer "B.SilkS")
		)
		(fp_line
			(start 1.603248 -1.500124)
			(end -1.603248 -1.500124)
			(stroke
				(width 0.1524)
				(type default)
			)
			(layer "B.SilkS")
		)
		(fp_line
			(start -0.700024 1.500124)
			(end -0.700024 0.219964)
			(stroke
				(width 0.1)
				(type default)
			)
			(layer "B.Fab")
		)
		(fp_line
			(start 0.700024 1.500124)
			(end -0.700024 1.500124)
			(stroke
				(width 0.1)
				(type default)
			)
			(layer "B.Fab")
		)
		(fp_line
			(start 0.700024 1.169924)
			(end 0.700024 1.500124)
			(stroke
				(width 0.1)
				(type default)
			)
			(layer "B.Fab")
		)
		(fp_line
			(start 1.249934 1.169924)
			(end 0.700024 1.169924)
			(stroke
				(width 0.1)
				(type default)
			)
			(layer "B.Fab")
		)
		(fp_line
			(start 0.6985 0.729996)
			(end 1.249934 0.729996)
			(stroke
				(width 0.1)
				(type default)
			)
			(layer "B.Fab")
		)
		(fp_line
			(start 1.249934 0.729996)
			(end 1.249934 1.169924)
			(stroke
				(width 0.1)
				(type default)
			)
			(layer "B.Fab")
		)
		(fp_line
			(start -1.249934 0.219964)
			(end -1.249934 -0.219964)
			(stroke
				(width 0.1)
				(type default)
			)
			(layer "B.Fab")
		)
		(fp_line
			(start -0.700024 0.219964)
			(end -1.249934 0.219964)
			(stroke
				(width 0.1)
				(type default)
			)
			(layer "B.Fab")
		)
		(fp_line
			(start -1.249934 -0.219964)
			(end -0.700024 -0.219964)
			(stroke
				(width 0.1)
				(type default)
			)
			(layer "B.Fab")
		)
		(fp_line
			(start -0.700024 -0.219964)
			(end -0.700024 -1.500124)
			(stroke
				(width 0.1)
				(type default)
			)
			(layer "B.Fab")
		)
		(fp_line
			(start 0.6985 -0.729996)
			(end 0.6985 0.729996)
			(stroke
				(width 0.1)
				(type default)
			)
			(layer "B.Fab")
		)
		(fp_line
			(start 1.249934 -0.729996)
			(end 0.6985 -0.729996)
			(stroke
				(width 0.1)
				(type default)
			)
			(layer "B.Fab")
		)
		(fp_line
			(start 0.700024 -1.169924)
			(end 1.249934 -1.169924)
			(stroke
				(width 0.1)
				(type default)
			)
			(layer "B.Fab")
		)
		(fp_line
			(start 1.249934 -1.169924)
			(end 1.249934 -0.729996)
			(stroke
				(width 0.1)
				(type default)
			)
			(layer "B.Fab")
		)
		(fp_line
			(start -0.700024 -1.500124)
			(end 0.700024 -1.500124)
			(stroke
				(width 0.1)
				(type default)
			)
			(layer "B.Fab")
		)
		(fp_line
			(start 0.700024 -1.500124)
			(end 0.700024 -1.169924)
			(stroke
				(width 0.1)
				(type default)
			)
			(layer "B.Fab")
		)
		(fp_rect
			(start 0.700024 1.500124)
			(end -0.700024 -1.500124)
			(stroke
				(width 0)
				(type default)
			)
			(fill no)
			(layer "B.Fab")
		)
		(pad "D" smd rect
			(at -0.999998 0 180)
			(size 0.8128 0.9144)
			(layers "B.Cu" "B.Mask" "B.Paste")
			(net "P52V_HS1_EN_BUF_DELAY")
		)
		(pad "G" smd rect
			(at 0.999998 -0.94996 180)
			(size 0.8128 0.9144)
			(layers "B.Cu" "B.Mask" "B.Paste")
			(net "P52V_HS1_EN_DELAY_N")
		)
		(pad "S" smd rect
			(at 0.999998 0.94996 180)
			(size 0.8128 0.9144)
			(layers "B.Cu" "B.Mask" "B.Paste")
			(net "GND")
		)
	)
	(footprint ""
		(layer "B.Cu")
		(at 240.538 -70.993 -90)
		(property "Reference" "R65"
			(at 0 0 90)
			(layer "B.SilkS")
			(hide yes)
			(effects
				(font
					(size 1.27 1.27)
				)
				(justify mirror)
			)
		)
		(property "Value" ""
			(at 0 0 90)
			(layer "B.Fab")
			(effects
				(font
					(size 1.27 1.27)
				)
				(justify mirror)
			)
		)
		(duplicate_pad_numbers_are_jumpers no)
		(fp_line
			(start -0.7874 0.4064)
			(end 0.7874 0.4064)
			(stroke
				(width 0.1524)
				(type default)
			)
			(layer "B.SilkS")
		)
		(fp_line
			(start 0.7874 0.4064)
			(end 0.7874 -0.4064)
			(stroke
				(width 0.1524)
				(type default)
			)
			(layer "B.SilkS")
		)
		(fp_line
			(start -0.7874 -0.4064)
			(end -0.7874 0.4064)
			(stroke
				(width 0.1524)
				(type default)
			)
			(layer "B.SilkS")
		)
		(fp_line
			(start 0.7874 -0.4064)
			(end -0.7874 -0.4064)
			(stroke
				(width 0.1524)
				(type default)
			)
			(layer "B.SilkS")
		)
		(fp_line
			(start -0.67945 0.3048)
			(end -0.120396 0.3048)
			(stroke
				(width 0.1)
				(type default)
			)
			(layer "B.Fab")
		)
		(fp_line
			(start -0.120396 0.3048)
			(end -0.120396 0.2794)
			(stroke
				(width 0.1)
				(type default)
			)
			(layer "B.Fab")
		)
		(fp_line
			(start 0.12065 0.3048)
			(end 0.67945 0.3048)
			(stroke
				(width 0.1)
				(type default)
			)
			(layer "B.Fab")
		)
		(fp_line
			(start 0.67945 0.3048)
			(end 0.67945 -0.305054)
			(stroke
				(width 0.1)
				(type default)
			)
			(layer "B.Fab")
		)
		(fp_line
			(start -0.120396 0.2794)
			(end 0.12065 0.2794)
			(stroke
				(width 0.1)
				(type default)
			)
			(layer "B.Fab")
		)
		(fp_line
			(start 0.12065 0.2794)
			(end 0.12065 0.3048)
			(stroke
				(width 0.1)
				(type default)
			)
			(layer "B.Fab")
		)
		(fp_line
			(start -0.12065 -0.2794)
			(end -0.12065 -0.3048)
			(stroke
				(width 0.1)
				(type default)
			)
			(layer "B.Fab")
		)
		(fp_line
			(start 0.12065 -0.2794)
			(end -0.12065 -0.2794)
			(stroke
				(width 0.1)
				(type default)
			)
			(layer "B.Fab")
		)
		(fp_line
			(start -0.67945 -0.3048)
			(end -0.67945 0.3048)
			(stroke
				(width 0.1)
				(type default)
			)
			(layer "B.Fab")
		)
		(fp_line
			(start -0.12065 -0.3048)
			(end -0.67945 -0.3048)
			(stroke
				(width 0.1)
				(type default)
			)
			(layer "B.Fab")
		)
		(fp_line
			(start 0.12065 -0.305054)
			(end 0.12065 -0.2794)
			(stroke
				(width 0.1)
				(type default)
			)
			(layer "B.Fab")
		)
		(fp_line
			(start 0.67945 -0.305054)
			(end 0.12065 -0.305054)
			(stroke
				(width 0.1)
				(type default)
			)
			(layer "B.Fab")
		)
		(pad "1" smd circle
			(at 0.40005 0 90)
			(size 0 0)
			(layers "B.Cu" "B.Mask" "B.Paste")
			(net "SMB_MB_PDB_R_SCL")
		)
		(pad "2" smd circle
			(at -0.40005 0 90)
			(size 0 0)
			(layers "B.Cu" "B.Mask" "B.Paste")
			(net "SMB_MB_PDB_SCL")
		)
	)
	(footprint ""
		(layer "B.Cu")
		(at 202.946 -89.408 180)
		(property "Reference" "R100"
			(at 0 0 0)
			(layer "B.SilkS")
			(hide yes)
			(effects
				(font
					(size 1.27 1.27)
				)
				(justify mirror)
			)
		)
		(property "Value" ""
			(at 0 0 0)
			(layer "B.Fab")
			(effects
				(font
					(size 1.27 1.27)
				)
				(justify mirror)
			)
		)
		(duplicate_pad_numbers_are_jumpers no)
		(fp_line
			(start 0.7874 0.4064)
			(end 0.7874 -0.4064)
			(stroke
				(width 0.1524)
				(type default)
			)
			(layer "B.SilkS")
		)
		(fp_line
			(start 0.7874 -0.4064)
			(end -0.7874 -0.4064)
			(stroke
				(width 0.1524)
				(type default)
			)
			(layer "B.SilkS")
		)
		(fp_line
			(start -0.7874 0.4064)
			(end 0.7874 0.4064)
			(stroke
				(width 0.1524)
				(type default)
			)
			(layer "B.SilkS")
		)
		(fp_line
			(start -0.7874 -0.4064)
			(end -0.7874 0.4064)
			(stroke
				(width 0.1524)
				(type default)
			)
			(layer "B.SilkS")
		)
		(fp_line
			(start 0.67945 0.3048)
			(end 0.67945 -0.305054)
			(stroke
				(width 0.1)
				(type default)
			)
			(layer "B.Fab")
		)
		(fp_line
			(start 0.67945 -0.305054)
			(end 0.12065 -0.305054)
			(stroke
				(width 0.1)
				(type default)
			)
			(layer "B.Fab")
		)
		(fp_line
			(start 0.12065 0.3048)
			(end 0.67945 0.3048)
			(stroke
				(width 0.1)
				(type default)
			)
			(layer "B.Fab")
		)
		(fp_line
			(start 0.12065 0.2794)
			(end 0.12065 0.3048)
			(stroke
				(width 0.1)
				(type default)
			)
			(layer "B.Fab")
		)
		(fp_line
			(start 0.12065 -0.2794)
			(end -0.12065 -0.2794)
			(stroke
				(width 0.1)
				(type default)
			)
			(layer "B.Fab")
		)
		(fp_line
			(start 0.12065 -0.305054)
			(end 0.12065 -0.2794)
			(stroke
				(width 0.1)
				(type default)
			)
			(layer "B.Fab")
		)
		(fp_line
			(start -0.120396 0.3048)
			(end -0.120396 0.2794)
			(stroke
				(width 0.1)
				(type default)
			)
			(layer "B.Fab")
		)
		(fp_line
			(start -0.120396 0.2794)
			(end 0.12065 0.2794)
			(stroke
				(width 0.1)
				(type default)
			)
			(layer "B.Fab")
		)
		(fp_line
			(start -0.12065 -0.2794)
			(end -0.12065 -0.3048)
			(stroke
				(width 0.1)
				(type default)
			)
			(layer "B.Fab")
		)
		(fp_line
			(start -0.12065 -0.3048)
			(end -0.67945 -0.3048)
			(stroke
				(width 0.1)
				(type default)
			)
			(layer "B.Fab")
		)
		(fp_line
			(start -0.67945 0.3048)
			(end -0.120396 0.3048)
			(stroke
				(width 0.1)
				(type default)
			)
			(layer "B.Fab")
		)
		(fp_line
			(start -0.67945 -0.3048)
			(end -0.67945 0.3048)
			(stroke
				(width 0.1)
				(type default)
			)
			(layer "B.Fab")
		)
		(pad "1" smd circle
			(at 0.40005 0)
			(size 0 0)
			(layers "B.Cu" "B.Mask" "B.Paste")
			(net "PU_9543_0_INT0")
		)
		(pad "2" smd circle
			(at -0.40005 0)
			(size 0 0)
			(layers "B.Cu" "B.Mask" "B.Paste")
			(net "P3V3_AUX")
		)
	)
	(footprint ""
		(layer "B.Cu")
		(at 291.719 -35.052)
		(property "Reference" "U36"
			(at -2.57937 1.1049 270)
			(unlocked yes)
			(layer "B.SilkS")
			(effects
				(font
					(size 0.7874 0.5842)
					(thickness 0.1524)
				)
				(justify left mirror)
			)
		)
		(property "Value" ""
			(at 0 0 0)
			(layer "B.Fab")
			(effects
				(font
					(size 1.27 1.27)
				)
				(justify mirror)
			)
		)
		(duplicate_pad_numbers_are_jumpers no)
		(fp_line
			(start -1.603248 -1.500124)
			(end -1.603248 1.500124)
			(stroke
				(width 0.1524)
				(type default)
			)
			(layer "B.SilkS")
		)
		(fp_line
			(start -1.603248 1.500124)
			(end 1.603248 1.500124)
			(stroke
				(width 0.1524)
				(type default)
			)
			(layer "B.SilkS")
		)
		(fp_line
			(start 1.603248 -1.500124)
			(end -1.603248 -1.500124)
			(stroke
				(width 0.1524)
				(type default)
			)
			(layer "B.SilkS")
		)
		(fp_line
			(start 1.603248 1.500124)
			(end 1.603248 -1.500124)
			(stroke
				(width 0.1524)
				(type default)
			)
			(layer "B.SilkS")
		)
		(fp_line
			(start -1.249934 -0.219964)
			(end -0.700024 -0.219964)
			(stroke
				(width 0.1)
				(type default)
			)
			(layer "B.Fab")
		)
		(fp_line
			(start -1.249934 0.219964)
			(end -1.249934 -0.219964)
			(stroke
				(width 0.1)
				(type default)
			)
			(layer "B.Fab")
		)
		(fp_line
			(start -0.700024 -1.500124)
			(end 0.700024 -1.500124)
			(stroke
				(width 0.1)
				(type default)
			)
			(layer "B.Fab")
		)
		(fp_line
			(start -0.700024 -0.219964)
			(end -0.700024 -1.500124)
			(stroke
				(width 0.1)
				(type default)
			)
			(layer "B.Fab")
		)
		(fp_line
			(start -0.700024 0.219964)
			(end -1.249934 0.219964)
			(stroke
				(width 0.1)
				(type default)
			)
			(layer "B.Fab")
		)
		(fp_line
			(start -0.700024 1.500124)
			(end -0.700024 0.219964)
			(stroke
				(width 0.1)
				(type default)
			)
			(layer "B.Fab")
		)
		(fp_line
			(start 0.6985 -0.729996)
			(end 0.6985 0.729996)
			(stroke
				(width 0.1)
				(type default)
			)
			(layer "B.Fab")
		)
		(fp_line
			(start 0.6985 0.729996)
			(end 1.249934 0.729996)
			(stroke
				(width 0.1)
				(type default)
			)
			(layer "B.Fab")
		)
		(fp_line
			(start 0.700024 -1.500124)
			(end 0.700024 -1.169924)
			(stroke
				(width 0.1)
				(type default)
			)
			(layer "B.Fab")
		)
		(fp_line
			(start 0.700024 -1.169924)
			(end 1.249934 -1.169924)
			(stroke
				(width 0.1)
				(type default)
			)
			(layer "B.Fab")
		)
		(fp_line
			(start 0.700024 1.169924)
			(end 0.700024 1.500124)
			(stroke
				(width 0.1)
				(type default)
			)
			(layer "B.Fab")
		)
		(fp_line
			(start 0.700024 1.500124)
			(end -0.700024 1.500124)
			(stroke
				(width 0.1)
				(type default)
			)
			(layer "B.Fab")
		)
		(fp_line
			(start 1.249934 -1.169924)
			(end 1.249934 -0.729996)
			(stroke
				(width 0.1)
				(type default)
			)
			(layer "B.Fab")
		)
		(fp_line
			(start 1.249934 -0.729996)
			(end 0.6985 -0.729996)
			(stroke
				(width 0.1)
				(type default)
			)
			(layer "B.Fab")
		)
		(fp_line
			(start 1.249934 0.729996)
			(end 1.249934 1.169924)
			(stroke
				(width 0.1)
				(type default)
			)
			(layer "B.Fab")
		)
		(fp_line
			(start 1.249934 1.169924)
			(end 0.700024 1.169924)
			(stroke
				(width 0.1)
				(type default)
			)
			(layer "B.Fab")
		)
		(fp_rect
			(start 0.700024 1.500124)
			(end -0.700024 -1.500124)
			(stroke
				(width 0)
				(type default)
			)
			(fill no)
			(layer "B.Fab")
		)
		(pad "D" smd rect
			(at -0.999998 0 270)
			(size 0.8128 0.9144)
			(layers "B.Cu" "B.Mask" "B.Paste")
			(net "FM_AC_PWR_CYCLE_BUF")
		)
		(pad "G" smd rect
			(at 0.999998 -0.94996 270)
			(size 0.8128 0.9144)
			(layers "B.Cu" "B.Mask" "B.Paste")
			(net "FM_AC_PWR_CYCLE_R1_N")
		)
		(pad "S" smd rect
			(at 0.999998 0.94996 270)
			(size 0.8128 0.9144)
			(layers "B.Cu" "B.Mask" "B.Paste")
			(net "GND")
		)
	)
	(footprint ""
		(layer "B.Cu")
		(at 96.849946 -114.046 90)
		(property "Reference" "C56"
			(at 0 0 90)
			(layer "B.SilkS")
			(hide yes)
			(effects
				(font
					(size 1.27 1.27)
				)
				(justify mirror)
			)
		)
		(property "Value" ""
			(at 0 0 90)
			(layer "B.Fab")
			(effects
				(font
					(size 1.27 1.27)
				)
				(justify mirror)
			)
		)
		(duplicate_pad_numbers_are_jumpers no)
		(fp_line
			(start 0.7874 -0.4064)
			(end -0.7874 -0.4064)
			(stroke
				(width 0.1524)
				(type default)
			)
			(layer "B.SilkS")
		)
		(fp_line
			(start -0.7874 -0.4064)
			(end -0.7874 0.4064)
			(stroke
				(width 0.1524)
				(type default)
			)
			(layer "B.SilkS")
		)
		(fp_line
			(start 0.7874 0.4064)
			(end 0.7874 -0.4064)
			(stroke
				(width 0.1524)
				(type default)
			)
			(layer "B.SilkS")
		)
		(fp_line
			(start -0.7874 0.4064)
			(end 0.7874 0.4064)
			(stroke
				(width 0.1524)
				(type default)
			)
			(layer "B.SilkS")
		)
		(fp_line
			(start 0.67945 -0.305054)
			(end 0.12065 -0.305054)
			(stroke
				(width 0.1)
				(type default)
			)
			(layer "B.Fab")
		)
		(fp_line
			(start 0.12065 -0.305054)
			(end 0.12065 -0.2794)
			(stroke
				(width 0.1)
				(type default)
			)
			(layer "B.Fab")
		)
		(fp_line
			(start -0.12065 -0.3048)
			(end -0.67945 -0.3048)
			(stroke
				(width 0.1)
				(type default)
			)
			(layer "B.Fab")
		)
		(fp_line
			(start -0.67945 -0.3048)
			(end -0.67945 0.3048)
			(stroke
				(width 0.1)
				(type default)
			)
			(layer "B.Fab")
		)
		(fp_line
			(start 0.12065 -0.2794)
			(end -0.12065 -0.2794)
			(stroke
				(width 0.1)
				(type default)
			)
			(layer "B.Fab")
		)
		(fp_line
			(start -0.12065 -0.2794)
			(end -0.12065 -0.3048)
			(stroke
				(width 0.1)
				(type default)
			)
			(layer "B.Fab")
		)
		(fp_line
			(start 0.12065 0.2794)
			(end 0.12065 0.3048)
			(stroke
				(width 0.1)
				(type default)
			)
			(layer "B.Fab")
		)
		(fp_line
			(start -0.120396 0.2794)
			(end 0.12065 0.2794)
			(stroke
				(width 0.1)
				(type default)
			)
			(layer "B.Fab")
		)
		(fp_line
			(start 0.67945 0.3048)
			(end 0.67945 -0.305054)
			(stroke
				(width 0.1)
				(type default)
			)
			(layer "B.Fab")
		)
		(fp_line
			(start 0.12065 0.3048)
			(end 0.67945 0.3048)
			(stroke
				(width 0.1)
				(type default)
			)
			(layer "B.Fab")
		)
		(fp_line
			(start -0.120396 0.3048)
			(end -0.120396 0.2794)
			(stroke
				(width 0.1)
				(type default)
			)
			(layer "B.Fab")
		)
		(fp_line
			(start -0.67945 0.3048)
			(end -0.120396 0.3048)
			(stroke
				(width 0.1)
				(type default)
			)
			(layer "B.Fab")
		)
		(pad "1" smd circle
			(at 0.40005 0 270)
			(size 0 0)
			(layers "B.Cu" "B.Mask" "B.Paste")
			(net "BRICK_P12V_1_EN_N")
		)
		(pad "2" smd circle
			(at -0.40005 0 270)
			(size 0 0)
			(layers "B.Cu" "B.Mask" "B.Paste")
			(net "GND")
		)
	)
)
